(kicad_pcb
	(version 20260206)
	(generator "pcbnew")
	(generator_version "10.0")
	(general
		(thickness 1.6)
		(legacy_teardrops no)
	)
	(paper "A4")
	(title_block
		(title "Bryce Canyon_R.DPB_16317-1_OCP.brd")
		(comment 1 "Bryce Canyon / footprints 2053-2060 of 2099")
	)
	(layers
		(0 "F.Cu" signal "TOP")
		(4 "In1.Cu" signal "L2GND")
		(6 "In2.Cu" signal "L3")
		(8 "In3.Cu" signal "L4VCC")
		(10 "In4.Cu" signal "L5VCC")
		(12 "In5.Cu" signal "L6")
		(14 "In6.Cu" signal "L7GND")
		(2 "B.Cu" signal "BOTTOM")
		(9 "F.Adhes" user "F.Adhesive")
		(11 "B.Adhes" user "B.Adhesive")
		(13 "F.Paste" user "Package Geometry/Pastemask Top")
		(15 "B.Paste" user "Package Geometry/Pastemask Bottom")
		(5 "F.SilkS" user "Ref Des/Silkscreen Top")
		(7 "B.SilkS" user "Ref Des/Silkscreen Bottom")
		(1 "F.Mask" user "Board Geometry/Soldermask Top")
		(3 "B.Mask" user "Board Geometry/Soldermask Bottom")
		(17 "Dwgs.User" user "User.Drawings")
		(19 "Cmts.User" user "User.Comments")
		(21 "Eco1.User" user "User.Eco1")
		(23 "Eco2.User" user "User.Eco2")
		(25 "Edge.Cuts" user "Board Geometry/Outline")
		(27 "Margin" user)
		(31 "F.CrtYd" user "Package Geometry/Place Bound Top")
		(29 "B.CrtYd" user "Package Geometry/Place Bound Bottom")
		(35 "F.Fab" user "Ref Des/Assembly Top")
		(33 "B.Fab" user "Ref Des/Assembly Bottom")
	)
	(footprint ""
		(layer "B.Cu")
		(at 437.834786 -119.229378)
		(property "Reference" "G8"
			(at 0 0 0)
			(layer "B.SilkS")
			(hide yes)
			(effects
				(font
					(size 1.27 1.27)
				)
				(justify mirror)
			)
		)
		(property "Value" "COPPER-CLOSE-GP-U"
			(at -0.0762 -2.8702 0)
			(unlocked yes)
			(layer "B.Fab")
			(hide yes)
			(effects
				(font
					(size 1.016 1.016)
					(thickness 0.1524)
				)
				(justify mirror)
			)
		)
		(property "Device Type" "CON2C-U"
			(at -0.0762 -4.3942 0)
			(unlocked yes)
			(layer "B.Fab")
			(hide yes)
			(effects
				(font
					(size 1.016 1.016)
					(thickness 0.1524)
				)
				(justify mirror)
			)
		)
		(duplicate_pad_numbers_are_jumpers no)
		(fp_rect
			(start 0.9398 0.9652)
			(end -0.9398 -0.9652)
			(stroke
				(width 0)
				(type default)
			)
			(fill no)
			(layer "B.CrtYd")
		)
		(fp_rect
			(start 0.9398 0.9652)
			(end -0.9398 -0.9652)
			(stroke
				(width 0)
				(type default)
			)
			(fill no)
			(layer "B.Fab")
		)
		(pad "1" smd custom
			(at 0 -0.5334 180)
			(size 0.17145 0.17145)
			(layers "B.Cu" "B.Mask" "B.Paste")
			(net "AGND_P5V_B_4")
			(options
				(clearance outline)
				(anchor circle)
			)
			(primitives
				(gr_poly
					(pts
						(xy -0.127 -0.3429) (xy -0.127 -0.1651) (xy -0.635 0.3429) (xy 0.635 0.3429) (xy 0.127 -0.1651)
						(xy 0.127 -0.3429)
					)
					(width 0)
					(fill yes)
				)
			)
		)
		(pad "2" smd custom
			(at 0 0.5334 180)
			(size 0.17145 0.17145)
			(layers "B.Cu" "B.Mask" "B.Paste")
			(net "GND")
			(options
				(clearance outline)
				(anchor circle)
			)
			(primitives
				(gr_poly
					(pts
						(xy -0.635 -0.3429) (xy -0.127 0.1651) (xy -0.127 0.3429) (xy 0.127 0.3429) (xy 0.127 0.1651)
						(xy 0.635 -0.3429)
					)
					(width 0)
					(fill yes)
				)
			)
		)
	)
	(footprint ""
		(layer "B.Cu")
		(at 218.207844 -329.057)
		(property "Reference" "C568"
			(at 0 0 0)
			(layer "B.SilkS")
			(hide yes)
			(effects
				(font
					(size 1.27 1.27)
				)
				(justify mirror)
			)
		)
		(property "Value" "SC22U25V6KX-2-GP-U"
			(at 2.860802 -5.279644 0)
			(unlocked yes)
			(layer "B.Fab")
			(hide yes)
			(effects
				(font
					(size 1.016 1.016)
					(thickness 0.1524)
				)
				(justify mirror)
			)
		)
		(property "Device Type" "C1206-TO0D3H75"
			(at 2.860802 -6.803644 0)
			(unlocked yes)
			(layer "B.Fab")
			(hide yes)
			(effects
				(font
					(size 1.016 1.016)
					(thickness 0.1524)
				)
				(justify mirror)
			)
		)
		(duplicate_pad_numbers_are_jumpers no)
		(fp_line
			(start -1.3081 -2.3749)
			(end -1.3081 2.3749)
			(stroke
				(width 0.1524)
				(type default)
			)
			(layer "B.SilkS")
		)
		(fp_line
			(start -1.3081 2.3749)
			(end 1.3081 2.3749)
			(stroke
				(width 0.1524)
				(type default)
			)
			(layer "B.SilkS")
		)
		(fp_line
			(start 1.3081 -2.3749)
			(end -1.3081 -2.3749)
			(stroke
				(width 0.1524)
				(type default)
			)
			(layer "B.SilkS")
		)
		(fp_line
			(start 1.3081 2.3749)
			(end 1.3081 -2.3749)
			(stroke
				(width 0.1524)
				(type default)
			)
			(layer "B.SilkS")
		)
		(fp_rect
			(start 0.8001 1.6002)
			(end -0.8001 -1.6002)
			(stroke
				(width 0)
				(type default)
			)
			(fill no)
			(layer "B.CrtYd")
		)
		(fp_poly
			(pts
				(xy 1.5621 2.4511) (xy 1.5621 1.6002) (xy -0.8001 1.6002) (xy -0.8001 -1.6002) (xy 0.8001 -1.6002)
				(xy 0.8001 1.5875) (xy 1.5621 1.5875) (xy 1.5621 -2.4511) (xy -1.5621 -2.4511) (xy -1.5621 2.4511)
			)
			(stroke
				(width 0)
				(type default)
			)
			(fill no)
			(layer "B.CrtYd")
		)
		(fp_rect
			(start 1.5621 2.4511)
			(end -1.5621 -2.4511)
			(stroke
				(width 0)
				(type default)
			)
			(fill no)
			(layer "B.Fab")
		)
		(pad "1" smd rect
			(at 0 -1.392936 180)
			(size 2.1082 1.4478)
			(layers "B.Cu" "B.Mask" "B.Paste")
			(net "P12V_IN")
		)
		(pad "2" smd rect
			(at 0 1.392936 180)
			(size 2.1082 1.4478)
			(layers "B.Cu" "B.Mask" "B.Paste")
			(net "GND")
		)
	)
	(footprint ""
		(layer "B.Cu")
		(at 15.433802 -227.08235 -90)
		(property "Reference" "C624"
			(at 0 0 90)
			(layer "B.SilkS")
			(hide yes)
			(effects
				(font
					(size 1.27 1.27)
				)
				(justify mirror)
			)
		)
		(property "Value" "SC4D7U25V5KX-1-GP"
			(at 0.0762 -6.1214 270)
			(unlocked yes)
			(layer "B.Fab")
			(hide yes)
			(effects
				(font
					(size 1.016 1.016)
					(thickness 0.1524)
				)
				(justify mirror)
			)
		)
		(property "Device Type" "C805H58"
			(at 0.0762 -8.1534 270)
			(unlocked yes)
			(layer "B.Fab")
			(hide yes)
			(effects
				(font
					(size 1.016 1.016)
					(thickness 0.1524)
				)
				(justify mirror)
			)
		)
		(duplicate_pad_numbers_are_jumpers no)
		(fp_line
			(start -0.635 0)
			(end 0.635 0)
			(stroke
				(width 0.508)
				(type default)
			)
			(layer "B.SilkS")
		)
		(fp_rect
			(start 0.9652 1.778)
			(end -0.9652 -1.778)
			(stroke
				(width 0)
				(type default)
			)
			(fill no)
			(layer "B.CrtYd")
		)
		(fp_poly
			(pts
				(xy 0.9652 -1.778) (xy -0.9652 -1.778) (xy -0.9652 1.778) (xy 0.9652 1.778)
			)
			(stroke
				(width 0)
				(type default)
			)
			(fill no)
			(layer "B.Fab")
		)
		(pad "1" smd rect
			(at 0 -0.9652 90)
			(size 1.397 1.143)
			(layers "B.Cu" "B.Mask" "B.Paste")
			(net "P12V_B_1_VDD_U31")
		)
		(pad "2" smd rect
			(at 0 0.9652 90)
			(size 1.397 1.143)
			(layers "B.Cu" "B.Mask" "B.Paste")
			(net "GND")
		)
	)
	(footprint ""
		(layer "B.Cu")
		(at 439.302398 -119.227092 180)
		(property "Reference" "R1171"
			(at 0 0 0)
			(layer "B.SilkS")
			(hide yes)
			(effects
				(font
					(size 1.27 1.27)
				)
				(justify mirror)
			)
		)
		(property "Value" "10KR2F-2-GP"
			(at -0.064008 -3.993896 180)
			(unlocked yes)
			(layer "B.Fab")
			(hide yes)
			(effects
				(font
					(size 1.016 1.016)
					(thickness 0.1524)
				)
				(justify mirror)
			)
		)
		(property "Device Type" "R402H16"
			(at -0.064008 -5.517896 180)
			(unlocked yes)
			(layer "B.Fab")
			(hide yes)
			(effects
				(font
					(size 1.016 1.016)
					(thickness 0.1524)
				)
				(justify mirror)
			)
		)
		(duplicate_pad_numbers_are_jumpers no)
		(fp_line
			(start 0.508 -0.9398)
			(end 0.508 0.9398)
			(stroke
				(width 0.1524)
				(type default)
			)
			(layer "B.SilkS")
		)
		(fp_line
			(start -0.508 -0.9398)
			(end 0.508 -0.9398)
			(stroke
				(width 0.1524)
				(type default)
			)
			(layer "B.SilkS")
		)
		(fp_rect
			(start 0.508 0.9398)
			(end -0.508 -0.9398)
			(stroke
				(width 0)
				(type default)
			)
			(fill no)
			(layer "B.CrtYd")
		)
		(fp_rect
			(start 0.508 0.9398)
			(end -0.508 -0.9398)
			(stroke
				(width 0)
				(type default)
			)
			(fill no)
			(layer "B.Fab")
		)
		(pad "1" smd custom
			(at 0 -0.4445)
			(size 0.1397 0.1397)
			(layers "B.Cu" "B.Mask" "B.Paste")
			(net "P5V_B_4_VFB")
			(options
				(clearance outline)
				(anchor circle)
			)
			(primitives
				(gr_poly
					(pts
						(arc
							(start -0.1778 0.2794)
							(mid -0.249642 0.249642)
							(end -0.2794 0.1778)
						)
						(arc
							(start -0.2794 -0.1778)
							(mid -0.249642 -0.249642)
							(end -0.1778 -0.2794)
						)
						(arc
							(start 0.1778 -0.2794)
							(mid 0.249642 -0.249642)
							(end 0.2794 -0.1778)
						)
						(arc
							(start 0.2794 0.1778)
							(mid 0.249642 0.249642)
							(end 0.1778 0.2794)
						)
					)
					(width 0)
					(fill yes)
				)
			)
		)
		(pad "2" smd custom
			(at 0 0.4445)
			(size 0.1397 0.1397)
			(layers "B.Cu" "B.Mask" "B.Paste")
			(net "AGND_P5V_B_4")
			(options
				(clearance outline)
				(anchor circle)
			)
			(primitives
				(gr_poly
					(pts
						(arc
							(start -0.1778 0.2794)
							(mid -0.249642 0.249642)
							(end -0.2794 0.1778)
						)
						(arc
							(start -0.2794 -0.1778)
							(mid -0.249642 -0.249642)
							(end -0.1778 -0.2794)
						)
						(arc
							(start 0.1778 -0.2794)
							(mid 0.249642 -0.249642)
							(end 0.2794 -0.1778)
						)
						(arc
							(start 0.2794 0.1778)
							(mid 0.249642 0.249642)
							(end 0.1778 0.2794)
						)
					)
					(width 0)
					(fill yes)
				)
			)
		)
	)
	(footprint ""
		(layer "B.Cu")
		(at 9.210802 -220.09735 90)
		(property "Reference" "L1"
			(at 0 0 90)
			(layer "B.SilkS")
			(hide yes)
			(effects
				(font
					(size 1.27 1.27)
				)
				(justify mirror)
			)
		)
		(property "Value" "BLM21PG220SN1DGP"
			(at -0.0254 -5.6896 90)
			(unlocked yes)
			(layer "B.Fab")
			(hide yes)
			(effects
				(font
					(size 1.016 1.016)
					(thickness 0.1524)
				)
				(justify mirror)
			)
		)
		(property "Device Type" "L20125H42"
			(at -0.0254 -7.5946 90)
			(unlocked yes)
			(layer "B.Fab")
			(hide yes)
			(effects
				(font
					(size 1.016 1.016)
					(thickness 0.1524)
				)
				(justify mirror)
			)
		)
		(duplicate_pad_numbers_are_jumpers no)
		(fp_line
			(start 0.9144 -1.7018)
			(end 0.9144 1.7018)
			(stroke
				(width 0.1524)
				(type default)
			)
			(layer "B.SilkS")
		)
		(fp_line
			(start -0.9144 -1.7018)
			(end 0.9144 -1.7018)
			(stroke
				(width 0.1524)
				(type default)
			)
			(layer "B.SilkS")
		)
		(fp_line
			(start 0.9144 1.7018)
			(end -0.9144 1.7018)
			(stroke
				(width 0.1524)
				(type default)
			)
			(layer "B.SilkS")
		)
		(fp_line
			(start -0.9144 1.7018)
			(end -0.9144 -1.7018)
			(stroke
				(width 0.1524)
				(type default)
			)
			(layer "B.SilkS")
		)
		(fp_rect
			(start 1.0033 1.778)
			(end -1.0033 -1.778)
			(stroke
				(width 0)
				(type default)
			)
			(fill no)
			(layer "B.CrtYd")
		)
		(fp_poly
			(pts
				(xy 1.0033 -1.778) (xy -1.0033 -1.778) (xy -1.0033 1.778) (xy 1.0033 1.778)
			)
			(stroke
				(width 0)
				(type default)
			)
			(fill no)
			(layer "B.Fab")
		)
		(pad "1" smd rect
			(at 0 -0.9652 270)
			(size 1.397 1.143)
			(layers "B.Cu" "B.Mask" "B.Paste")
			(net "P12V_B")
		)
		(pad "2" smd rect
			(at 0 0.9652 270)
			(size 1.397 1.143)
			(layers "B.Cu" "B.Mask" "B.Paste")
			(net "P12V_B_1_VIN_U31")
		)
	)
	(footprint ""
		(layer "B.Cu")
		(at 460.060802 -230.63835 90)
		(property "Reference" "C666"
			(at 0 0 90)
			(layer "B.SilkS")
			(hide yes)
			(effects
				(font
					(size 1.27 1.27)
				)
				(justify mirror)
			)
		)
		(property "Value" "SC68P50V2JN-2-GP"
			(at -1.1811 -2.7051 90)
			(unlocked yes)
			(layer "B.Fab")
			(hide yes)
			(effects
				(font
					(size 1.016 1.016)
					(thickness 0.1524)
				)
				(justify mirror)
			)
		)
		(property "Device Type" "C402H22"
			(at -1.1811 -4.2291 90)
			(unlocked yes)
			(layer "B.Fab")
			(hide yes)
			(effects
				(font
					(size 1.016 1.016)
					(thickness 0.1524)
				)
				(justify mirror)
			)
		)
		(duplicate_pad_numbers_are_jumpers no)
		(fp_rect
			(start 0.4318 0.9525)
			(end -0.4318 -0.9525)
			(stroke
				(width 0)
				(type default)
			)
			(fill no)
			(layer "B.CrtYd")
		)
		(fp_rect
			(start 0.4318 0.9525)
			(end -0.4318 -0.9525)
			(stroke
				(width 0)
				(type default)
			)
			(fill no)
			(layer "B.Fab")
		)
		(pad "1" smd custom
			(at 0 -0.4445 270)
			(size 0.1524 0.1524)
			(layers "B.Cu" "B.Mask" "B.Paste")
			(net "P5V_B_3_VFB")
			(options
				(clearance outline)
				(anchor circle)
			)
			(primitives
				(gr_poly
					(pts
						(arc
							(start 0.3048 0.2032)
							(mid 0.275042 0.275042)
							(end 0.2032 0.3048)
						)
						(arc
							(start -0.2032 0.3048)
							(mid -0.275042 0.275042)
							(end -0.3048 0.2032)
						)
						(arc
							(start -0.3048 -0.2032)
							(mid -0.275042 -0.275042)
							(end -0.2032 -0.3048)
						)
						(arc
							(start 0.2032 -0.3048)
							(mid 0.275042 -0.275042)
							(end 0.3048 -0.2032)
						)
					)
					(width 0)
					(fill yes)
				)
			)
		)
		(pad "2" smd custom
			(at 0 0.4445 270)
			(size 0.1524 0.1524)
			(layers "B.Cu" "B.Mask" "B.Paste")
			(net "P5V_B_3_VFB_R")
			(options
				(clearance outline)
				(anchor circle)
			)
			(primitives
				(gr_poly
					(pts
						(arc
							(start 0.3048 0.2032)
							(mid 0.275042 0.275042)
							(end 0.2032 0.3048)
						)
						(arc
							(start -0.2032 0.3048)
							(mid -0.275042 0.275042)
							(end -0.3048 0.2032)
						)
						(arc
							(start -0.3048 -0.2032)
							(mid -0.275042 -0.275042)
							(end -0.2032 -0.3048)
						)
						(arc
							(start 0.2032 -0.3048)
							(mid 0.275042 -0.275042)
							(end 0.3048 -0.2032)
						)
					)
					(width 0)
					(fill yes)
				)
			)
		)
	)
	(footprint ""
		(layer "B.Cu")
		(at 458.201014 -229.543864 180)
		(property "Reference" "R1150"
			(at 0 0 0)
			(layer "B.SilkS")
			(hide yes)
			(effects
				(font
					(size 1.27 1.27)
				)
				(justify mirror)
			)
		)
		(property "Value" "10KR2F-2-GP"
			(at -0.064008 -3.993896 180)
			(unlocked yes)
			(layer "B.Fab")
			(hide yes)
			(effects
				(font
					(size 1.016 1.016)
					(thickness 0.1524)
				)
				(justify mirror)
			)
		)
		(property "Device Type" "R402H16"
			(at -0.064008 -5.517896 180)
			(unlocked yes)
			(layer "B.Fab")
			(hide yes)
			(effects
				(font
					(size 1.016 1.016)
					(thickness 0.1524)
				)
				(justify mirror)
			)
		)
		(duplicate_pad_numbers_are_jumpers no)
		(fp_line
			(start 0.508 -0.9398)
			(end 0.508 0.9398)
			(stroke
				(width 0.1524)
				(type default)
			)
			(layer "B.SilkS")
		)
		(fp_line
			(start -0.508 -0.9398)
			(end 0.508 -0.9398)
			(stroke
				(width 0.1524)
				(type default)
			)
			(layer "B.SilkS")
		)
		(fp_rect
			(start 0.508 0.9398)
			(end -0.508 -0.9398)
			(stroke
				(width 0)
				(type default)
			)
			(fill no)
			(layer "B.CrtYd")
		)
		(fp_rect
			(start 0.508 0.9398)
			(end -0.508 -0.9398)
			(stroke
				(width 0)
				(type default)
			)
			(fill no)
			(layer "B.Fab")
		)
		(pad "1" smd custom
			(at 0 -0.4445)
			(size 0.1397 0.1397)
			(layers "B.Cu" "B.Mask" "B.Paste")
			(net "P5V_B_3_VFB")
			(options
				(clearance outline)
				(anchor circle)
			)
			(primitives
				(gr_poly
					(pts
						(arc
							(start -0.1778 0.2794)
							(mid -0.249642 0.249642)
							(end -0.2794 0.1778)
						)
						(arc
							(start -0.2794 -0.1778)
							(mid -0.249642 -0.249642)
							(end -0.1778 -0.2794)
						)
						(arc
							(start 0.1778 -0.2794)
							(mid 0.249642 -0.249642)
							(end 0.2794 -0.1778)
						)
						(arc
							(start 0.2794 0.1778)
							(mid 0.249642 0.249642)
							(end 0.1778 0.2794)
						)
					)
					(width 0)
					(fill yes)
				)
			)
		)
		(pad "2" smd custom
			(at 0 0.4445)
			(size 0.1397 0.1397)
			(layers "B.Cu" "B.Mask" "B.Paste")
			(net "AGND_P5V_B_3")
			(options
				(clearance outline)
				(anchor circle)
			)
			(primitives
				(gr_poly
					(pts
						(arc
							(start -0.1778 0.2794)
							(mid -0.249642 0.249642)
							(end -0.2794 0.1778)
						)
						(arc
							(start -0.2794 -0.1778)
							(mid -0.249642 -0.249642)
							(end -0.1778 -0.2794)
						)
						(arc
							(start 0.1778 -0.2794)
							(mid 0.249642 -0.249642)
							(end 0.2794 -0.1778)
						)
						(arc
							(start 0.2794 0.1778)
							(mid 0.249642 0.249642)
							(end 0.1778 0.2794)
						)
					)
					(width 0)
					(fill yes)
				)
			)
		)
	)
	(footprint ""
		(layer "B.Cu")
		(at 34.82086 -108.988606 90)
		(property "Reference" "L3"
			(at 0 0 90)
			(layer "B.SilkS")
			(hide yes)
			(effects
				(font
					(size 1.27 1.27)
				)
				(justify mirror)
			)
		)
		(property "Value" "BLM21PG220SN1DGP"
			(at -0.0254 -5.6896 90)
			(unlocked yes)
			(layer "B.Fab")
			(hide yes)
			(effects
				(font
					(size 1.016 1.016)
					(thickness 0.1524)
				)
				(justify mirror)
			)
		)
		(property "Device Type" "L20125H42"
			(at -0.0254 -7.5946 90)
			(unlocked yes)
			(layer "B.Fab")
			(hide yes)
			(effects
				(font
					(size 1.016 1.016)
					(thickness 0.1524)
				)
				(justify mirror)
			)
		)
		(duplicate_pad_numbers_are_jumpers no)
		(fp_line
			(start 0.9144 -1.7018)
			(end 0.9144 1.7018)
			(stroke
				(width 0.1524)
				(type default)
			)
			(layer "B.SilkS")
		)
		(fp_line
			(start -0.9144 -1.7018)
			(end 0.9144 -1.7018)
			(stroke
				(width 0.1524)
				(type default)
			)
			(layer "B.SilkS")
		)
		(fp_line
			(start 0.9144 1.7018)
			(end -0.9144 1.7018)
			(stroke
				(width 0.1524)
				(type default)
			)
			(layer "B.SilkS")
		)
		(fp_line
			(start -0.9144 1.7018)
			(end -0.9144 -1.7018)
			(stroke
				(width 0.1524)
				(type default)
			)
			(layer "B.SilkS")
		)
		(fp_rect
			(start 1.0033 1.778)
			(end -1.0033 -1.778)
			(stroke
				(width 0)
				(type default)
			)
			(fill no)
			(layer "B.CrtYd")
		)
		(fp_poly
			(pts
				(xy 1.0033 -1.778) (xy -1.0033 -1.778) (xy -1.0033 1.778) (xy 1.0033 1.778)
			)
			(stroke
				(width 0)
				(type default)
			)
			(fill no)
			(layer "B.Fab")
		)
		(pad "1" smd rect
			(at 0 -0.9652 270)
			(size 1.397 1.143)
			(layers "B.Cu" "B.Mask" "B.Paste")
			(net "P12V_B")
		)
		(pad "2" smd rect
			(at 0 0.9652 270)
			(size 1.397 1.143)
			(layers "B.Cu" "B.Mask" "B.Paste")
			(net "P12V_B_2_VIN_U32")
		)
	)
)
